(kicad_pcb
	(version 20260206)
	(generator "pcbnew")
	(generator_version "10.0")
	(general
		(thickness 1.6)
		(legacy_teardrops no)
	)
	(paper "A4")
	(title_block
		(title "baseboard — 13948-1b.1110WZS1818.brd")
		(comment 1 "Honey Badger (Wiwynn) / footprints 1728-1733 of 2523")
	)
	(layers
		(0 "F.Cu" signal "TOP")
		(4 "In1.Cu" signal "L2GND")
		(6 "In2.Cu" signal "L3")
		(8 "In3.Cu" signal "L4VCC")
		(10 "In4.Cu" signal "L5VCC")
		(12 "In5.Cu" signal "L6")
		(14 "In6.Cu" signal "L7GND")
		(2 "B.Cu" signal "BOTTOM")
		(9 "F.Adhes" user "F.Adhesive")
		(11 "B.Adhes" user "B.Adhesive")
		(13 "F.Paste" user "Package Geometry/Pastemask Top")
		(15 "B.Paste" user "Package Geometry/Pastemask Bottom")
		(5 "F.SilkS" user "Ref Des/Silkscreen Top")
		(7 "B.SilkS" user "Ref Des/Silkscreen Bottom")
		(1 "F.Mask" user "Board Geometry/Soldermask Top")
		(3 "B.Mask" user "Board Geometry/Soldermask Bottom")
		(17 "Dwgs.User" user "User.Drawings")
		(19 "Cmts.User" user "User.Comments")
		(21 "Eco1.User" user "User.Eco1")
		(23 "Eco2.User" user "User.Eco2")
		(25 "Edge.Cuts" user "Board Geometry/Outline")
		(27 "Margin" user)
		(31 "F.CrtYd" user "Package Geometry/Place Bound Top")
		(29 "B.CrtYd" user "Package Geometry/Place Bound Bottom")
		(35 "F.Fab" user "Ref Des/Assembly Top")
		(33 "B.Fab" user "Ref Des/Assembly Bottom")
	)
	(footprint ""
		(layer "F.Cu")
		(at 9.856216 -226.62388 180)
		(property "Reference" "R518"
			(at 0 0 180)
			(layer "F.SilkS")
			(hide yes)
			(effects
				(font
					(size 1.27 1.27)
				)
			)
		)
		(property "Value" "27KR2F-L-GP"
			(at 0.064008 -3.993896 180)
			(unlocked yes)
			(layer "F.Fab")
			(hide yes)
			(effects
				(font
					(size 1.016 1.016)
					(thickness 0.1524)
				)
			)
		)
		(property "Device Type" "R402H16"
			(at 0.064008 -5.517896 180)
			(unlocked yes)
			(layer "F.Fab")
			(hide yes)
			(effects
				(font
					(size 1.016 1.016)
					(thickness 0.1524)
				)
			)
		)
		(duplicate_pad_numbers_are_jumpers no)
		(fp_line
			(start 0.508 -0.9398)
			(end -0.508 -0.9398)
			(stroke
				(width 0.1524)
				(type default)
			)
			(layer "F.SilkS")
		)
		(fp_line
			(start -0.508 -0.9398)
			(end -0.508 0.9398)
			(stroke
				(width 0.1524)
				(type default)
			)
			(layer "F.SilkS")
		)
		(fp_rect
			(start -0.508 0.9398)
			(end 0.508 -0.9398)
			(stroke
				(width 0)
				(type default)
			)
			(fill no)
			(layer "F.CrtYd")
		)
		(fp_rect
			(start -0.508 0.9398)
			(end 0.508 -0.9398)
			(stroke
				(width 0)
				(type default)
			)
			(fill no)
			(layer "F.Fab")
		)
		(pad "1" smd custom
			(at 0 -0.4445 180)
			(size 0.1397 0.1397)
			(layers "F.Cu" "F.Mask" "F.Paste")
			(net "P12V_PCIE")
			(options
				(clearance outline)
				(anchor circle)
			)
			(primitives
				(gr_poly
					(pts
						(arc
							(start -0.1778 -0.2794)
							(mid -0.249642 -0.249642)
							(end -0.2794 -0.1778)
						)
						(arc
							(start -0.2794 0.1778)
							(mid -0.249642 0.249642)
							(end -0.1778 0.2794)
						)
						(arc
							(start 0.1778 0.2794)
							(mid 0.249642 0.249642)
							(end 0.2794 0.1778)
						)
						(arc
							(start 0.2794 -0.1778)
							(mid 0.249642 -0.249642)
							(end 0.1778 -0.2794)
						)
					)
					(width 0)
					(fill yes)
				)
			)
		)
		(pad "2" smd custom
			(at 0 0.4445 180)
			(size 0.1397 0.1397)
			(layers "F.Cu" "F.Mask" "F.Paste")
			(net "PCIE_MATED#_A")
			(options
				(clearance outline)
				(anchor circle)
			)
			(primitives
				(gr_poly
					(pts
						(arc
							(start -0.1778 -0.2794)
							(mid -0.249642 -0.249642)
							(end -0.2794 -0.1778)
						)
						(arc
							(start -0.2794 0.1778)
							(mid -0.249642 0.249642)
							(end -0.1778 0.2794)
						)
						(arc
							(start 0.1778 0.2794)
							(mid 0.249642 0.249642)
							(end 0.2794 0.1778)
						)
						(arc
							(start 0.2794 -0.1778)
							(mid 0.249642 -0.249642)
							(end 0.1778 -0.2794)
						)
					)
					(width 0)
					(fill yes)
				)
			)
		)
	)
	(footprint ""
		(layer "F.Cu")
		(at 45.654722 -139.546584 180)
		(property "Reference" "SU76"
			(at 0 0 180)
			(layer "F.SilkS")
			(hide yes)
			(effects
				(font
					(size 1.27 1.27)
				)
			)
		)
		(property "Value" "SOLVC2G07DBVR-GP"
			(at -0.0254 -11.9634 180)
			(unlocked yes)
			(layer "F.Fab")
			(hide yes)
			(effects
				(font
					(size 1.016 1.016)
					(thickness 0.1524)
				)
			)
		)
		(property "Device Type" "SOT-6H58"
			(at -0.0254 -13.5636 180)
			(unlocked yes)
			(layer "F.Fab")
			(hide yes)
			(effects
				(font
					(size 1.016 1.016)
					(thickness 0.1524)
				)
			)
		)
		(duplicate_pad_numbers_are_jumpers no)
		(fp_line
			(start 1.7145 0.5842)
			(end 1.7145 -0.5842)
			(stroke
				(width 0.1524)
				(type default)
			)
			(layer "F.SilkS")
		)
		(fp_line
			(start 1.7145 -0.5842)
			(end -1.9685 -0.5842)
			(stroke
				(width 0.1524)
				(type default)
			)
			(layer "F.SilkS")
		)
		(fp_line
			(start -1.5621 0)
			(end -1.9685 0.4064)
			(stroke
				(width 0.1524)
				(type default)
			)
			(layer "F.SilkS")
		)
		(fp_line
			(start -1.9685 0.5842)
			(end 1.7145 0.5842)
			(stroke
				(width 0.1524)
				(type default)
			)
			(layer "F.SilkS")
		)
		(fp_line
			(start -1.9685 0.5842)
			(end -1.9685 2.3622)
			(stroke
				(width 0.508)
				(type default)
			)
			(layer "F.SilkS")
		)
		(fp_line
			(start -1.9685 -0.4064)
			(end -1.5621 0)
			(stroke
				(width 0.1524)
				(type default)
			)
			(layer "F.SilkS")
		)
		(fp_line
			(start -1.9685 -0.5842)
			(end -1.9685 0.5842)
			(stroke
				(width 0.1524)
				(type default)
			)
			(layer "F.SilkS")
		)
		(fp_poly
			(pts
				(xy -1.27 -0.635) (xy 1.27 -0.635) (xy 1.27 0.635) (xy -1.27 0.635)
			)
			(stroke
				(width 0)
				(type default)
			)
			(fill yes)
			(layer "F.SilkS")
		)
		(fp_rect
			(start -1.9685 2.3622)
			(end 1.9685 -2.3622)
			(stroke
				(width 0)
				(type default)
			)
			(fill no)
			(layer "F.CrtYd")
		)
		(fp_poly
			(pts
				(xy -1.9685 -2.3622) (xy 1.9685 -2.3622) (xy 1.9685 2.3622) (xy -1.9685 2.3622)
			)
			(stroke
				(width 0)
				(type default)
			)
			(fill no)
			(layer "F.Fab")
		)
		(pad "1" smd rect
			(at -0.9525 1.3462 180)
			(size 0.5842 1.016)
			(layers "F.Cu" "F.Mask" "F.Paste")
			(net "EXP_RESET_N")
		)
		(pad "2" smd rect
			(at 0 1.3462 180)
			(size 0.5842 1.016)
			(layers "F.Cu" "F.Mask" "F.Paste")
			(net "GND")
		)
		(pad "3" smd rect
			(at 0.9525 1.3462 180)
			(size 0.5842 1.016)
			(layers "F.Cu" "F.Mask" "F.Paste")
			(net "ICE_RESET_N")
		)
		(pad "4" smd rect
			(at 0.9525 -1.3462 180)
			(size 0.5842 1.016)
			(layers "F.Cu" "F.Mask" "F.Paste")
			(net "RESET_AND_N")
		)
		(pad "5" smd rect
			(at 0 -1.3462 180)
			(size 0.5842 1.016)
			(layers "F.Cu" "F.Mask" "F.Paste")
			(net "P1V8_STBY")
		)
		(pad "6" smd rect
			(at -0.9525 -1.3462 180)
			(size 0.5842 1.016)
			(layers "F.Cu" "F.Mask" "F.Paste")
			(net "RESET_AND_N")
		)
	)
	(footprint ""
		(layer "F.Cu")
		(at 99.32797 -76.454 180)
		(property "Reference" "SR771"
			(at 0 0 180)
			(layer "F.SilkS")
			(hide yes)
			(effects
				(font
					(size 1.27 1.27)
				)
			)
		)
		(property "Value" "4K75R2F-1-GP"
			(at 0.064008 -3.993896 180)
			(unlocked yes)
			(layer "F.Fab")
			(hide yes)
			(effects
				(font
					(size 1.016 1.016)
					(thickness 0.1524)
				)
			)
		)
		(property "Device Type" "R402H16"
			(at 0.064008 -5.517896 180)
			(unlocked yes)
			(layer "F.Fab")
			(hide yes)
			(effects
				(font
					(size 1.016 1.016)
					(thickness 0.1524)
				)
			)
		)
		(duplicate_pad_numbers_are_jumpers no)
		(fp_line
			(start 0.508 -0.9398)
			(end -0.508 -0.9398)
			(stroke
				(width 0.1524)
				(type default)
			)
			(layer "F.SilkS")
		)
		(fp_line
			(start -0.508 -0.9398)
			(end -0.508 0.9398)
			(stroke
				(width 0.1524)
				(type default)
			)
			(layer "F.SilkS")
		)
		(fp_rect
			(start -0.508 0.9398)
			(end 0.508 -0.9398)
			(stroke
				(width 0)
				(type default)
			)
			(fill no)
			(layer "F.CrtYd")
		)
		(fp_rect
			(start -0.508 0.9398)
			(end 0.508 -0.9398)
			(stroke
				(width 0)
				(type default)
			)
			(fill no)
			(layer "F.Fab")
		)
		(pad "1" smd custom
			(at 0 -0.4445 180)
			(size 0.1397 0.1397)
			(layers "F.Cu" "F.Mask" "F.Paste")
			(net "P1V8_E")
			(options
				(clearance outline)
				(anchor circle)
			)
			(primitives
				(gr_poly
					(pts
						(arc
							(start -0.1778 -0.2794)
							(mid -0.249642 -0.249642)
							(end -0.2794 -0.1778)
						)
						(arc
							(start -0.2794 0.1778)
							(mid -0.249642 0.249642)
							(end -0.1778 0.2794)
						)
						(arc
							(start 0.1778 0.2794)
							(mid 0.249642 0.249642)
							(end 0.2794 0.1778)
						)
						(arc
							(start 0.2794 -0.1778)
							(mid 0.249642 -0.249642)
							(end 0.1778 -0.2794)
						)
					)
					(width 0)
					(fill yes)
				)
			)
		)
		(pad "2" smd custom
			(at 0 0.4445 180)
			(size 0.1397 0.1397)
			(layers "F.Cu" "F.Mask" "F.Paste")
			(net "SXP_ACTIVE_0")
			(options
				(clearance outline)
				(anchor circle)
			)
			(primitives
				(gr_poly
					(pts
						(arc
							(start -0.1778 -0.2794)
							(mid -0.249642 -0.249642)
							(end -0.2794 -0.1778)
						)
						(arc
							(start -0.2794 0.1778)
							(mid -0.249642 0.249642)
							(end -0.1778 0.2794)
						)
						(arc
							(start 0.1778 0.2794)
							(mid 0.249642 0.249642)
							(end 0.2794 0.1778)
						)
						(arc
							(start 0.2794 -0.1778)
							(mid 0.249642 -0.249642)
							(end 0.1778 -0.2794)
						)
					)
					(width 0)
					(fill yes)
				)
			)
		)
	)
	(footprint ""
		(layer "F.Cu")
		(at 220.599 -121.158 90)
		(property "Reference" "Q80"
			(at 0 0 90)
			(layer "F.SilkS")
			(hide yes)
			(effects
				(font
					(size 1.27 1.27)
				)
			)
		)
		(property "Value" "MMBT3904TT1G-GP"
			(at 0 -9.7282 90)
			(unlocked yes)
			(layer "F.Fab")
			(hide yes)
			(effects
				(font
					(size 1.016 1.016)
					(thickness 0.1524)
				)
			)
		)
		(property "Device Type" "SC75CBE1D6H36"
			(at 0 -11.6332 90)
			(unlocked yes)
			(layer "F.Fab")
			(hide yes)
			(effects
				(font
					(size 1.016 1.016)
					(thickness 0.1524)
				)
			)
		)
		(duplicate_pad_numbers_are_jumpers no)
		(fp_line
			(start 0.9652 -1.3716)
			(end -0.9652 -1.3716)
			(stroke
				(width 0.1524)
				(type default)
			)
			(layer "F.SilkS")
		)
		(fp_line
			(start -0.9652 -1.3716)
			(end -0.9652 1.3716)
			(stroke
				(width 0.1524)
				(type default)
			)
			(layer "F.SilkS")
		)
		(fp_line
			(start 0.9652 1.3716)
			(end 0.9652 -1.3716)
			(stroke
				(width 0.1524)
				(type default)
			)
			(layer "F.SilkS")
		)
		(fp_line
			(start -0.9652 1.3716)
			(end 0.9652 1.3716)
			(stroke
				(width 0.1524)
				(type default)
			)
			(layer "F.SilkS")
		)
		(fp_rect
			(start -1.0414 1.4478)
			(end 1.0414 -1.4478)
			(stroke
				(width 0)
				(type default)
			)
			(fill no)
			(layer "F.CrtYd")
		)
		(fp_poly
			(pts
				(xy -1.0414 -1.4478) (xy 1.0414 -1.4478) (xy 1.0414 1.4478) (xy -1.0414 1.4478)
			)
			(stroke
				(width 0)
				(type default)
			)
			(fill no)
			(layer "F.Fab")
		)
		(pad "B" smd custom
			(at -0.508 0.7112 90)
			(size 0.127 0.127)
			(layers "F.Cu" "F.Mask" "F.Paste")
			(net "P1V8_C_B")
			(options
				(clearance outline)
				(anchor circle)
			)
			(primitives
				(gr_poly
					(pts
						(arc
							(start -0.044958 0.4572)
							(mid -0.192463 0.399794)
							(end -0.254 0.254)
						)
						(xy -0.254 -0.254)
						(arc
							(start -0.253746 -0.254)
							(mid -0.192968 -0.398936)
							(end -0.04699 -0.4572)
						)
						(arc
							(start 0.04699 -0.4572)
							(mid 0.192989 -0.398958)
							(end 0.253746 -0.254)
						)
						(xy 0.254 -0.254)
						(arc
							(start 0.254 0.254)
							(mid 0.192404 0.399734)
							(end 0.044958 0.4572)
						)
					)
					(width 0)
					(fill yes)
				)
			)
		)
		(pad "C" smd custom
			(at 0 -0.7112 90)
			(size 0.127 0.127)
			(layers "F.Cu" "F.Mask" "F.Paste")
			(net "P3V3_STBY_R3")
			(options
				(clearance outline)
				(anchor circle)
			)
			(primitives
				(gr_poly
					(pts
						(arc
							(start -0.044958 0.4572)
							(mid -0.192463 0.399794)
							(end -0.254 0.254)
						)
						(xy -0.254 -0.254)
						(arc
							(start -0.253746 -0.254)
							(mid -0.192968 -0.398936)
							(end -0.04699 -0.4572)
						)
						(arc
							(start 0.04699 -0.4572)
							(mid 0.192989 -0.398958)
							(end 0.253746 -0.254)
						)
						(xy 0.254 -0.254)
						(arc
							(start 0.254 0.254)
							(mid 0.192404 0.399734)
							(end 0.044958 0.4572)
						)
					)
					(width 0)
					(fill yes)
				)
			)
		)
		(pad "E" smd custom
			(at 0.508 0.7112 90)
			(size 0.127 0.127)
			(layers "F.Cu" "F.Mask" "F.Paste")
			(net "GND")
			(options
				(clearance outline)
				(anchor circle)
			)
			(primitives
				(gr_poly
					(pts
						(arc
							(start -0.044958 0.4572)
							(mid -0.192463 0.399794)
							(end -0.254 0.254)
						)
						(xy -0.254 -0.254)
						(arc
							(start -0.253746 -0.254)
							(mid -0.192968 -0.398936)
							(end -0.04699 -0.4572)
						)
						(arc
							(start 0.04699 -0.4572)
							(mid 0.192989 -0.398958)
							(end 0.253746 -0.254)
						)
						(xy 0.254 -0.254)
						(arc
							(start 0.254 0.254)
							(mid 0.192404 0.399734)
							(end 0.044958 0.4572)
						)
					)
					(width 0)
					(fill yes)
				)
			)
		)
	)
	(footprint ""
		(layer "F.Cu")
		(at 257.302 -136.779)
		(property "Reference" "R7902"
			(at 0 0 0)
			(layer "F.SilkS")
			(hide yes)
			(effects
				(font
					(size 1.27 1.27)
				)
			)
		)
		(property "Value" "0R2J-2-GP"
			(at 0.064008 -3.993896 0)
			(unlocked yes)
			(layer "F.Fab")
			(hide yes)
			(effects
				(font
					(size 1.016 1.016)
					(thickness 0.1524)
				)
			)
		)
		(property "Device Type" "R402H16"
			(at 0.064008 -5.517896 0)
			(unlocked yes)
			(layer "F.Fab")
			(hide yes)
			(effects
				(font
					(size 1.016 1.016)
					(thickness 0.1524)
				)
			)
		)
		(duplicate_pad_numbers_are_jumpers no)
		(fp_line
			(start -0.508 -0.9398)
			(end -0.508 0.9398)
			(stroke
				(width 0.1524)
				(type default)
			)
			(layer "F.SilkS")
		)
		(fp_line
			(start 0.508 -0.9398)
			(end -0.508 -0.9398)
			(stroke
				(width 0.1524)
				(type default)
			)
			(layer "F.SilkS")
		)
		(fp_rect
			(start -0.508 0.9398)
			(end 0.508 -0.9398)
			(stroke
				(width 0)
				(type default)
			)
			(fill no)
			(layer "F.CrtYd")
		)
		(fp_rect
			(start -0.508 0.9398)
			(end 0.508 -0.9398)
			(stroke
				(width 0)
				(type default)
			)
			(fill no)
			(layer "F.Fab")
		)
		(pad "1" smd custom
			(at 0 -0.4445)
			(size 0.1397 0.1397)
			(layers "F.Cu" "F.Mask" "F.Paste")
			(net "CPU_S_TXD")
			(options
				(clearance outline)
				(anchor circle)
			)
			(primitives
				(gr_poly
					(pts
						(arc
							(start -0.1778 -0.2794)
							(mid -0.249642 -0.249642)
							(end -0.2794 -0.1778)
						)
						(arc
							(start -0.2794 0.1778)
							(mid -0.249642 0.249642)
							(end -0.1778 0.2794)
						)
						(arc
							(start 0.1778 0.2794)
							(mid 0.249642 0.249642)
							(end 0.2794 0.1778)
						)
						(arc
							(start 0.2794 -0.1778)
							(mid 0.249642 -0.249642)
							(end 0.1778 -0.2794)
						)
					)
					(width 0)
					(fill yes)
				)
			)
		)
		(pad "2" smd custom
			(at 0 0.4445)
			(size 0.1397 0.1397)
			(layers "F.Cu" "F.Mask" "F.Paste")
			(net "CPU_U192_PIN6_TX")
			(options
				(clearance outline)
				(anchor circle)
			)
			(primitives
				(gr_poly
					(pts
						(arc
							(start -0.1778 -0.2794)
							(mid -0.249642 -0.249642)
							(end -0.2794 -0.1778)
						)
						(arc
							(start -0.2794 0.1778)
							(mid -0.249642 0.249642)
							(end -0.1778 0.2794)
						)
						(arc
							(start 0.1778 0.2794)
							(mid 0.249642 0.249642)
							(end 0.2794 0.1778)
						)
						(arc
							(start 0.2794 -0.1778)
							(mid 0.249642 -0.249642)
							(end 0.1778 -0.2794)
						)
					)
					(width 0)
					(fill yes)
				)
			)
		)
	)
	(footprint ""
		(layer "F.Cu")
		(at 294.513 -161.544 180)
		(property "Reference" "R283"
			(at 0 0 180)
			(layer "F.SilkS")
			(hide yes)
			(effects
				(font
					(size 1.27 1.27)
				)
			)
		)
		(property "Value" "0R2J-2-GP"
			(at 0.064008 -3.993896 180)
			(unlocked yes)
			(layer "F.Fab")
			(hide yes)
			(effects
				(font
					(size 1.016 1.016)
					(thickness 0.1524)
				)
			)
		)
		(property "Device Type" "R402H16"
			(at 0.064008 -5.517896 180)
			(unlocked yes)
			(layer "F.Fab")
			(hide yes)
			(effects
				(font
					(size 1.016 1.016)
					(thickness 0.1524)
				)
			)
		)
		(duplicate_pad_numbers_are_jumpers no)
		(fp_line
			(start 0.508 -0.9398)
			(end -0.508 -0.9398)
			(stroke
				(width 0.1524)
				(type default)
			)
			(layer "F.SilkS")
		)
		(fp_line
			(start -0.508 -0.9398)
			(end -0.508 0.9398)
			(stroke
				(width 0.1524)
				(type default)
			)
			(layer "F.SilkS")
		)
		(fp_rect
			(start -0.508 0.9398)
			(end 0.508 -0.9398)
			(stroke
				(width 0)
				(type default)
			)
			(fill no)
			(layer "F.CrtYd")
		)
		(fp_rect
			(start -0.508 0.9398)
			(end 0.508 -0.9398)
			(stroke
				(width 0)
				(type default)
			)
			(fill no)
			(layer "F.Fab")
		)
		(pad "1" smd custom
			(at 0 -0.4445 180)
			(size 0.1397 0.1397)
			(layers "F.Cu" "F.Mask" "F.Paste")
			(net "RMII_BMC_PHY_TXD0")
			(options
				(clearance outline)
				(anchor circle)
			)
			(primitives
				(gr_poly
					(pts
						(arc
							(start -0.1778 -0.2794)
							(mid -0.249642 -0.249642)
							(end -0.2794 -0.1778)
						)
						(arc
							(start -0.2794 0.1778)
							(mid -0.249642 0.249642)
							(end -0.1778 0.2794)
						)
						(arc
							(start 0.1778 0.2794)
							(mid 0.249642 0.249642)
							(end 0.2794 0.1778)
						)
						(arc
							(start 0.2794 -0.1778)
							(mid 0.249642 -0.249642)
							(end 0.1778 -0.2794)
						)
					)
					(width 0)
					(fill yes)
				)
			)
		)
		(pad "2" smd custom
			(at 0 0.4445 180)
			(size 0.1397 0.1397)
			(layers "F.Cu" "F.Mask" "F.Paste")
			(net "RMII0_BMC_C_PHY_TXD0")
			(options
				(clearance outline)
				(anchor circle)
			)
			(primitives
				(gr_poly
					(pts
						(arc
							(start -0.1778 -0.2794)
							(mid -0.249642 -0.249642)
							(end -0.2794 -0.1778)
						)
						(arc
							(start -0.2794 0.1778)
							(mid -0.249642 0.249642)
							(end -0.1778 0.2794)
						)
						(arc
							(start 0.1778 0.2794)
							(mid 0.249642 0.249642)
							(end 0.2794 0.1778)
						)
						(arc
							(start 0.2794 -0.1778)
							(mid 0.249642 -0.249642)
							(end 0.1778 -0.2794)
						)
					)
					(width 0)
					(fill yes)
				)
			)
		)
	)
)
